# TIMECARD (Time Appliance Project (Time Card)) — schematic netlist excerpt (pin names and nets, part order shuffled) for the footprints in the layout excerpt that follows; sources: Cadence DE-HDL packaged netlist, KiCad conversion of R4006-B0001-02_R01.brd

R416  RESISTOR  1KOHM 1%  pkg SMC_0402R_H016  page 17 : \1\ = UNNAMED_6_LM75BDPTSSOP8_I59_A0 ; \2\ = SG
R74  RESISTOR  4.7KOHM 1%  pkg SMC_0402R_H016  page 20 : \1\ = XP3R3V_FPGA ; \2\ = BNO080_I2C_SDA

(kicad_pcb
	(version 20260206)
	(generator "pcbnew")
	(generator_version "10.0")
	(general
		(thickness 1.6)
		(legacy_teardrops no)
	)
	(paper "A4")
	(title_block
		(title "timecard-production-celestica-r4006 — R4006-B0001-02_R01.brd")
		(comment 1 "Time Appliance Project (Time Card) / footprints 960-961 of 1113")
	)
	(layers
		(0 "F.Cu" signal "TOP")
		(4 "In1.Cu" signal "L02_GND1")
		(6 "In2.Cu" signal "L03_SIG1")
		(8 "In3.Cu" signal "L04_GND2")
		(10 "In4.Cu" signal "L05_VCC1")
		(12 "In5.Cu" signal "L06_VCC2")
		(14 "In6.Cu" signal "L07_GND3")
		(16 "In7.Cu" signal "L08_SIG2")
		(18 "In8.Cu" signal "L09_GND4")
		(2 "B.Cu" signal "BOTTOM")
		(9 "F.Adhes" user "F.Adhesive")
		(11 "B.Adhes" user "B.Adhesive")
		(13 "F.Paste" user "Package Geometry/Pastemask Top")
		(15 "B.Paste" user "Package Geometry/Pastemask Bottom")
		(5 "F.SilkS" user "Ref Des/Silkscreen Top")
		(7 "B.SilkS" user "Ref Des/Silkscreen Bottom")
		(1 "F.Mask" user "Board Geometry/Soldermask Top")
		(3 "B.Mask" user "Board Geometry/Soldermask Bottom")
		(17 "Dwgs.User" user "User.Drawings")
		(19 "Cmts.User" user "User.Comments")
		(21 "Eco1.User" user "User.Eco1")
		(23 "Eco2.User" user "User.Eco2")
		(25 "Edge.Cuts" user "Board Geometry/Outline")
		(27 "Margin" user)
		(31 "F.CrtYd" user "Package Geometry/Place Bound Top")
		(29 "B.CrtYd" user "Package Geometry/Place Bound Bottom")
		(35 "F.Fab" user "Ref Des/Assembly Top")
		(33 "B.Fab" user "Ref Des/Assembly Bottom")
	)
	(footprint ""
		(layer "B.Cu")
		(at 87.376 -57.277 180)
		(property "Reference" "R74"
			(at -1.778 -3.08737 0)
			(unlocked yes)
			(layer "B.SilkS")
			(effects
				(font
					(size 0.7874 0.5842)
					(thickness 0.1524)
				)
				(justify mirror)
			)
		)
		(property "Value" "VAL*"
			(at -0.02032 2.13233 180)
			(unlocked yes)
			(layer "B.Fab")
			(hide yes)
			(effects
				(font
					(size 0.7874 0.5842)
					(thickness 0.1524)
				)
				(justify mirror)
			)
		)
		(property "Device Type" "RESISTOR-G155-14701-01,4.7KOHMA"
			(at -0.008382 1.210564 180)
			(unlocked yes)
			(layer "B.Fab")
			(hide yes)
			(effects
				(font
					(size 0.7874 0.5842)
					(thickness 0.1524)
				)
				(justify mirror)
			)
		)
		(property "User Part Number" "PARTNUM*"
			(at -0.02032 4.024884 180)
			(unlocked yes)
			(layer "Cmts.User")
			(hide yes)
			(effects
				(font
					(size 0.7874 0.5842)
					(thickness 0.1524)
				)
				(justify mirror)
			)
		)
		(property "Tolerance" "TOL*"
			(at -0.044704 3.05435 180)
			(unlocked yes)
			(layer "Cmts.User")
			(hide yes)
			(effects
				(font
					(size 0.7874 0.5842)
					(thickness 0.1524)
				)
				(justify mirror)
			)
		)
		(duplicate_pad_numbers_are_jumpers no)
		(fp_line
			(start 1.143 0.5588)
			(end -1.143 0.5588)
			(stroke
				(width 0.1)
				(type default)
			)
			(layer "B.SilkS")
		)
		(fp_line
			(start 1.143 -0.5588)
			(end 1.143 0.5588)
			(stroke
				(width 0.1)
				(type default)
			)
			(layer "B.SilkS")
		)
		(fp_line
			(start -1.143 0.5588)
			(end -1.143 -0.5588)
			(stroke
				(width 0.1)
				(type default)
			)
			(layer "B.SilkS")
		)
		(fp_line
			(start -1.143 -0.5588)
			(end 1.143 -0.5588)
			(stroke
				(width 0.1)
				(type default)
			)
			(layer "B.SilkS")
		)
		(fp_rect
			(start -1.143 -0.5588)
			(end 1.143 0.5588)
			(stroke
				(width 0)
				(type default)
			)
			(fill no)
			(layer "B.CrtYd")
		)
		(fp_line
			(start 0.508 0.3048)
			(end -0.508 0.3048)
			(stroke
				(width 0.1)
				(type default)
			)
			(layer "B.Fab")
		)
		(fp_line
			(start 0.508 -0.3048)
			(end 0.508 0.3048)
			(stroke
				(width 0.1)
				(type default)
			)
			(layer "B.Fab")
		)
		(fp_line
			(start -0.508 0.3048)
			(end -0.508 -0.3048)
			(stroke
				(width 0.1)
				(type default)
			)
			(layer "B.Fab")
		)
		(fp_line
			(start -0.508 -0.3048)
			(end 0.508 -0.3048)
			(stroke
				(width 0.1)
				(type default)
			)
			(layer "B.Fab")
		)
		(pad "1" smd rect
			(at 0.5334 0)
			(size 0.7112 0.6096)
			(layers "B.Cu" "B.Mask" "B.Paste")
			(net "XP3R3V_FPGA")
		)
		(pad "2" smd rect
			(at -0.5334 0)
			(size 0.7112 0.6096)
			(layers "B.Cu" "B.Mask" "B.Paste")
			(net "BNO080_I2C_SDA")
		)
		(zone
			(layer "B.Cu")
			(hatch none 0.5)
			(connect_pads
				(clearance 0)
			)
			(min_thickness 0.25)
			(keepout
				(tracks allowed)
				(vias not_allowed)
				(pads allowed)
				(copperpour not_allowed)
				(footprints allowed)
			)
			(placement
				(enabled no)
				(sheetname "")
			)
			(fill
				(thermal_gap 0.5)
				(thermal_bridge_width 0.5)
				(island_removal_mode 0)
			)
			(polygon
				(pts
					(xy 87.4522 -56.9722) (xy 87.4522 -57.5818) (xy 87.2998 -57.5818) (xy 87.2998 -56.9722)
				)
			)
		)
	)
	(footprint ""
		(layer "B.Cu")
		(at 55.1942 -74.9808 90)
		(property "Reference" "R416"
			(at 4.064 0.08763 270)
			(unlocked yes)
			(layer "B.SilkS")
			(effects
				(font
					(size 0.7874 0.5842)
					(thickness 0.1524)
				)
				(justify mirror)
			)
		)
		(property "Value" "VAL*"
			(at -0.02032 2.13233 90)
			(unlocked yes)
			(layer "B.Fab")
			(hide yes)
			(effects
				(font
					(size 0.7874 0.5842)
					(thickness 0.1524)
				)
				(justify mirror)
			)
		)
		(property "Device Type" "RESISTOR-G155-11001-01,1KOHM,1%"
			(at -0.008382 1.210564 90)
			(unlocked yes)
			(layer "B.Fab")
			(hide yes)
			(effects
				(font
					(size 0.7874 0.5842)
					(thickness 0.1524)
				)
				(justify mirror)
			)
		)
		(property "User Part Number" "PARTNUM*"
			(at -0.02032 4.024884 90)
			(unlocked yes)
			(layer "Cmts.User")
			(hide yes)
			(effects
				(font
					(size 0.7874 0.5842)
					(thickness 0.1524)
				)
				(justify mirror)
			)
		)
		(property "Tolerance" "TOL*"
			(at -0.044704 3.05435 90)
			(unlocked yes)
			(layer "Cmts.User")
			(hide yes)
			(effects
				(font
					(size 0.7874 0.5842)
					(thickness 0.1524)
				)
				(justify mirror)
			)
		)
		(duplicate_pad_numbers_are_jumpers no)
		(fp_line
			(start 1.143 -0.5588)
			(end 1.143 0.5588)
			(stroke
				(width 0.1)
				(type default)
			)
			(layer "B.SilkS")
		)
		(fp_line
			(start -1.143 -0.5588)
			(end 1.143 -0.5588)
			(stroke
				(width 0.1)
				(type default)
			)
			(layer "B.SilkS")
		)
		(fp_line
			(start 1.143 0.5588)
			(end -1.143 0.5588)
			(stroke
				(width 0.1)
				(type default)
			)
			(layer "B.SilkS")
		)
		(fp_line
			(start -1.143 0.5588)
			(end -1.143 -0.5588)
			(stroke
				(width 0.1)
				(type default)
			)
			(layer "B.SilkS")
		)
		(fp_rect
			(start 1.143 0.5588)
			(end -1.143 -0.5588)
			(stroke
				(width 0)
				(type default)
			)
			(fill no)
			(layer "B.CrtYd")
		)
		(fp_line
			(start 0.508 -0.3048)
			(end 0.508 0.3048)
			(stroke
				(width 0.1)
				(type default)
			)
			(layer "B.Fab")
		)
		(fp_line
			(start -0.508 -0.3048)
			(end 0.508 -0.3048)
			(stroke
				(width 0.1)
				(type default)
			)
			(layer "B.Fab")
		)
		(fp_line
			(start 0.508 0.3048)
			(end -0.508 0.3048)
			(stroke
				(width 0.1)
				(type default)
			)
			(layer "B.Fab")
		)
		(fp_line
			(start -0.508 0.3048)
			(end -0.508 -0.3048)
			(stroke
				(width 0.1)
				(type default)
			)
			(layer "B.Fab")
		)
		(pad "1" smd rect
			(at 0.5334 0 270)
			(size 0.7112 0.6096)
			(layers "B.Cu" "B.Mask" "B.Paste")
			(net "UNNAMED_6_LM75BDPTSSOP8_I59_A0")
		)
		(pad "2" smd rect
			(at -0.5334 0 270)
			(size 0.7112 0.6096)
			(layers "B.Cu" "B.Mask" "B.Paste")
			(net "SG")
		)
		(zone
			(layer "B.Cu")
			(hatch none 0.5)
			(connect_pads
				(clearance 0)
			)
			(min_thickness 0.25)
			(keepout
				(tracks allowed)
				(vias not_allowed)
				(pads allowed)
				(copperpour not_allowed)
				(footprints allowed)
			)
			(placement
				(enabled no)
				(sheetname "")
			)
			(fill
				(thermal_gap 0.5)
				(thermal_bridge_width 0.5)
				(island_removal_mode 0)
			)
			(polygon
				(pts
					(xy 55.499 -75.057) (xy 54.8894 -75.057) (xy 54.8894 -74.9046) (xy 55.499 -74.9046)
				)
			)
		)
		(zone
			(layer "B.Cu")
			(hatch none 0.5)
			(connect_pads
				(clearance 0)
			)
			(min_thickness 0.25)
			(keepout
				(tracks not_allowed)
				(vias allowed)
				(pads allowed)
				(copperpour not_allowed)
				(footprints allowed)
			)
			(placement
				(enabled no)
				(sheetname "")
			)
			(fill
				(thermal_gap 0.5)
				(thermal_bridge_width 0.5)
				(island_removal_mode 0)
			)
			(polygon
				(pts
					(xy 55.499 -75.057) (xy 54.8894 -75.057) (xy 54.8894 -74.9046) (xy 55.499 -74.9046)
				)
			)
		)
	)
)
